(kicad_pcb
	(version 20260206)
	(generator "pcbnew")
	(generator_version "10.0")
	(general
		(thickness 1.6)
		(legacy_teardrops no)
	)
	(paper "A4")
	(title_block
		(title "9054_F0T_PDB_BD_GPU_F_V04_1213_1550_OCP.brd")
		(comment 1 "Grand Teton / footprints 592-593 of 608")
	)
	(layers
		(0 "F.Cu" signal "TOP")
		(4 "In1.Cu" signal "GND")
		(6 "In2.Cu" signal "IN1")
		(8 "In3.Cu" signal "GND1")
		(10 "In4.Cu" signal "VCC")
		(12 "In5.Cu" signal "VCC1")
		(14 "In6.Cu" signal "GND2")
		(16 "In7.Cu" signal "IN2")
		(18 "In8.Cu" signal "GND3")
		(2 "B.Cu" signal "BOTTOM")
		(9 "F.Adhes" user "F.Adhesive")
		(11 "B.Adhes" user "B.Adhesive")
		(13 "F.Paste" user "Package Geometry/Pastemask Top")
		(15 "B.Paste" user "Package Geometry/Pastemask Bottom")
		(5 "F.SilkS" user "Ref Des/Silkscreen Top")
		(7 "B.SilkS" user "Ref Des/Silkscreen Bottom")
		(1 "F.Mask" user "Board Geometry/Soldermask Top")
		(3 "B.Mask" user "Board Geometry/Soldermask Bottom")
		(17 "Dwgs.User" user "User.Drawings")
		(19 "Cmts.User" user "User.Comments")
		(21 "Eco1.User" user "User.Eco1")
		(23 "Eco2.User" user "User.Eco2")
		(25 "Edge.Cuts" user "Board Geometry/Outline")
		(27 "Margin" user)
		(31 "F.CrtYd" user "Package Geometry/Place Bound Top")
		(29 "B.CrtYd" user "Package Geometry/Place Bound Bottom")
		(35 "F.Fab" user "Ref Des/Assembly Top")
		(33 "B.Fab" user "Ref Des/Assembly Bottom")
	)
	(footprint ""
		(layer "B.Cu")
		(at 177.465736 -70.612 180)
		(property "Reference" "PU9"
			(at -3.699764 -5.24637 0)
			(unlocked yes)
			(layer "B.SilkS")
			(effects
				(font
					(size 0.7874 0.5842)
					(thickness 0.1524)
				)
				(justify left mirror)
			)
		)
		(property "Value" ""
			(at 0 0 0)
			(layer "B.Fab")
			(effects
				(font
					(size 1.27 1.27)
				)
				(justify mirror)
			)
		)
		(duplicate_pad_numbers_are_jumpers no)
		(fp_line
			(start 4.05003 3.549904)
			(end 3.5052 3.549904)
			(stroke
				(width 0.1524)
				(type default)
			)
			(layer "B.SilkS")
		)
		(fp_line
			(start 4.05003 3.0226)
			(end 4.05003 3.549904)
			(stroke
				(width 0.1524)
				(type default)
			)
			(layer "B.SilkS")
		)
		(fp_line
			(start 4.05003 -3.549904)
			(end 4.05003 -3.0226)
			(stroke
				(width 0.1524)
				(type default)
			)
			(layer "B.SilkS")
		)
		(fp_line
			(start 3.5052 -3.549904)
			(end 4.05003 -3.549904)
			(stroke
				(width 0.1524)
				(type default)
			)
			(layer "B.SilkS")
		)
		(fp_line
			(start -0.0254 3.549904)
			(end -0.9906 3.549904)
			(stroke
				(width 0.1524)
				(type default)
			)
			(layer "B.SilkS")
		)
		(fp_line
			(start -0.9906 -3.549904)
			(end -0.0254 -3.549904)
			(stroke
				(width 0.1524)
				(type default)
			)
			(layer "B.SilkS")
		)
		(fp_line
			(start -3.5052 3.549904)
			(end -4.05003 3.549904)
			(stroke
				(width 0.1524)
				(type default)
			)
			(layer "B.SilkS")
		)
		(fp_line
			(start -4.05003 3.549904)
			(end -4.05003 3.0226)
			(stroke
				(width 0.1524)
				(type default)
			)
			(layer "B.SilkS")
		)
		(fp_line
			(start -4.05003 -3.0226)
			(end -4.05003 -3.549904)
			(stroke
				(width 0.1524)
				(type default)
			)
			(layer "B.SilkS")
		)
		(fp_line
			(start -4.05003 -3.549904)
			(end -3.5052 -3.549904)
			(stroke
				(width 0.1524)
				(type default)
			)
			(layer "B.SilkS")
		)
		(fp_poly
			(pts
				(xy 4.706112 -4.300728) (xy 5.424424 -3.582162) (xy 4.346702 -3.223006)
			)
			(stroke
				(width 0)
				(type default)
			)
			(fill yes)
			(layer "B.SilkS")
		)
		(fp_line
			(start 4.05003 3.549904)
			(end -4.05003 3.549904)
			(stroke
				(width 0.1)
				(type default)
			)
			(layer "B.Fab")
		)
		(fp_line
			(start 4.05003 -3.549904)
			(end 4.05003 3.549904)
			(stroke
				(width 0.1)
				(type default)
			)
			(layer "B.Fab")
		)
		(fp_line
			(start -4.05003 3.549904)
			(end -4.05003 -3.549904)
			(stroke
				(width 0.1)
				(type default)
			)
			(layer "B.Fab")
		)
		(fp_line
			(start -4.05003 -3.549904)
			(end 4.05003 -3.549904)
			(stroke
				(width 0.1)
				(type default)
			)
			(layer "B.Fab")
		)
		(fp_poly
			(pts
				(xy 5.588 -3.25882) (xy 5.588 -2.24282) (xy 4.572 -2.75082)
			)
			(stroke
				(width 0)
				(type default)
			)
			(fill yes)
			(layer "B.Fab")
		)
		(pad "1" smd oval
			(at 3.9497 -2.75082 90)
			(size 0.3048 0.8382)
			(layers "B.Cu" "B.Mask" "B.Paste")
			(net "P52V_HS2_ISET")
		)
		(pad "2" smd oval
			(at 3.9497 -2.25044 90)
			(size 0.3048 0.8382)
			(layers "B.Cu" "B.Mask" "B.Paste")
			(net "P52V_HS2_ISTART")
		)
		(pad "3" smd oval
			(at 3.9497 -1.75006 90)
			(size 0.3048 0.8382)
			(layers "B.Cu" "B.Mask" "B.Paste")
			(net "P52V_HS2_VCAP")
		)
		(pad "4" smd oval
			(at 3.9497 -1.24968 90)
			(size 0.3048 0.8382)
			(layers "B.Cu" "B.Mask" "B.Paste")
			(net "P52V_HS2_ESTART_R")
		)
		(pad "5" smd oval
			(at 3.9497 -0.7493 90)
			(size 0.3048 0.8382)
			(layers "B.Cu" "B.Mask" "B.Paste")
			(net "P52V_HS2_EFAULT_R")
		)
		(pad "6" smd oval
			(at 3.9497 -0.24892 90)
			(size 0.3048 0.8382)
			(layers "B.Cu" "B.Mask" "B.Paste")
			(net "P52V_HS2_EN")
		)
		(pad "7" smd oval
			(at 3.9497 0.24892 90)
			(size 0.3048 0.8382)
			(layers "B.Cu" "B.Mask" "B.Paste")
			(net "P52V_HS2_ADR0")
		)
		(pad "8" smd oval
			(at 3.9497 0.7493 90)
			(size 0.3048 0.8382)
			(layers "B.Cu" "B.Mask" "B.Paste")
			(net "P52V_HS2_ADR1")
		)
		(pad "9" smd oval
			(at 3.9497 1.24968 90)
			(size 0.3048 0.8382)
			(layers "B.Cu" "B.Mask" "B.Paste")
			(net "SMB_P52V_PDB_SCL_R2")
		)
		(pad "10" smd oval
			(at 3.9497 1.75006 90)
			(size 0.3048 0.8382)
			(layers "B.Cu" "B.Mask" "B.Paste")
			(net "SMB_CM_HS2_3V3SB_DATI")
		)
		(pad "11" smd oval
			(at 3.9497 2.25044 90)
			(size 0.3048 0.8382)
			(layers "B.Cu" "B.Mask" "B.Paste")
			(net "SMB_CM_HS2_3V3SB_DATO")
		)
		(pad "12" smd oval
			(at 3.9497 2.75082 90)
			(size 0.3048 0.8382)
			(layers "B.Cu" "B.Mask" "B.Paste")
			(net "P52V_HS2_MCB")
		)
		(pad "13" smd oval
			(at 3.2512 3.44932)
			(size 0.3048 0.8382)
			(layers "B.Cu" "B.Mask" "B.Paste")
			(net "P52V_HS2_GPO2")
		)
		(pad "14" smd oval
			(at 2.75082 3.44932)
			(size 0.3048 0.8382)
			(layers "B.Cu" "B.Mask" "B.Paste")
			(net "P52V_HS2_GPO1")
		)
		(pad "15" smd oval
			(at 2.25044 3.44932)
			(size 0.3048 0.8382)
			(layers "B.Cu" "B.Mask" "B.Paste")
			(net "Net_407")
		)
		(pad "16" smd oval
			(at 1.75006 3.44932)
			(size 0.3048 0.8382)
			(layers "B.Cu" "B.Mask" "B.Paste")
			(net "Net_406")
		)
		(pad "17" smd oval
			(at 1.24968 3.44932)
			(size 0.3048 0.8382)
			(layers "B.Cu" "B.Mask" "B.Paste")
			(net "PWRGD_P52V_HS2_PG")
		)
		(pad "18" smd oval
			(at 0.7493 3.44932)
			(size 0.3048 0.8382)
			(layers "B.Cu" "B.Mask" "B.Paste")
			(net "P52V_HS2_PWRGIN")
		)
		(pad "19" smd oval
			(at 0.24892 3.44932)
			(size 0.3048 0.8382)
			(layers "B.Cu" "B.Mask" "B.Paste")
			(net "GND1_FIELD_SIGNAL")
		)
		(pad "20" smd oval
			(at -1.24968 3.44932)
			(size 0.3048 0.8382)
			(layers "B.Cu" "B.Mask" "B.Paste")
			(net "P52V_HS2_VCC")
		)
		(pad "21" smd oval
			(at -1.75006 3.44932)
			(size 0.3048 0.8382)
			(layers "B.Cu" "B.Mask" "B.Paste")
			(net "P52V_HS2_VCC")
		)
		(pad "22" smd oval
			(at -2.25044 3.44932)
			(size 0.3048 0.8382)
			(layers "B.Cu" "B.Mask" "B.Paste")
			(net "P52V_HS2_VCC")
		)
		(pad "23" smd oval
			(at -2.75082 3.44932)
			(size 0.3048 0.8382)
			(layers "B.Cu" "B.Mask" "B.Paste")
			(net "P52V_HS2_VCC")
		)
		(pad "24" smd oval
			(at -3.2512 3.44932)
			(size 0.3048 0.8382)
			(layers "B.Cu" "B.Mask" "B.Paste")
			(net "P52V_HS2_VCC")
		)
		(pad "25" smd oval
			(at -3.9497 2.75082 90)
			(size 0.3048 0.8382)
			(layers "B.Cu" "B.Mask" "B.Paste")
			(net "Net_23")
		)
		(pad "26" smd oval
			(at -3.9497 2.25044 90)
			(size 0.3048 0.8382)
			(layers "B.Cu" "B.Mask" "B.Paste")
			(net "Net_14")
		)
		(pad "27" smd oval
			(at -3.9497 1.75006 90)
			(size 0.3048 0.8382)
			(layers "B.Cu" "B.Mask" "B.Paste")
			(net "Net_6")
		)
		(pad "28" smd oval
			(at -3.9497 1.24968 90)
			(size 0.3048 0.8382)
			(layers "B.Cu" "B.Mask" "B.Paste")
			(net "Net_19")
		)
		(pad "29" smd oval
			(at -3.9497 0.7493 90)
			(size 0.3048 0.8382)
			(layers "B.Cu" "B.Mask" "B.Paste")
			(net "P52V_HS2_VCP")
		)
		(pad "30" smd oval
			(at -3.9497 0.24892 90)
			(size 0.3048 0.8382)
			(layers "B.Cu" "B.Mask" "B.Paste")
			(net "P52V_HS2_DV_DT_R")
		)
		(pad "31" smd oval
			(at -3.9497 -0.24892 90)
			(size 0.3048 0.8382)
			(layers "B.Cu" "B.Mask" "B.Paste")
			(net "P52V_HS2")
		)
		(pad "32" smd oval
			(at -3.9497 -0.7493 90)
			(size 0.3048 0.8382)
			(layers "B.Cu" "B.Mask" "B.Paste")
			(net "P52V_HS2_1272_GATE")
		)
		(pad "33" smd oval
			(at -3.9497 -1.24968 90)
			(size 0.3048 0.8382)
			(layers "B.Cu" "B.Mask" "B.Paste")
			(net "Net_5")
		)
		(pad "34" smd oval
			(at -3.9497 -1.75006 90)
			(size 0.3048 0.8382)
			(layers "B.Cu" "B.Mask" "B.Paste")
			(net "Net_11")
		)
		(pad "35" smd oval
			(at -3.9497 -2.25044 90)
			(size 0.3048 0.8382)
			(layers "B.Cu" "B.Mask" "B.Paste")
			(net "Net_7")
		)
		(pad "36" smd oval
			(at -3.9497 -2.75082 90)
			(size 0.3048 0.8382)
			(layers "B.Cu" "B.Mask" "B.Paste")
			(net "Net_10")
		)
		(pad "37" smd oval
			(at -3.2512 -3.44932)
			(size 0.3048 0.8382)
			(layers "B.Cu" "B.Mask" "B.Paste")
			(net "Net_22")
		)
		(pad "38" smd oval
			(at -2.75082 -3.44932)
			(size 0.3048 0.8382)
			(layers "B.Cu" "B.Mask" "B.Paste")
			(net "P52V_HS2_1272_S_N")
		)
		(pad "39" smd oval
			(at -2.25044 -3.44932)
			(size 0.3048 0.8382)
			(layers "B.Cu" "B.Mask" "B.Paste")
			(net "P52V_HS2_1272_S_P")
		)
		(pad "40" smd oval
			(at -1.75006 -3.44932)
			(size 0.3048 0.8382)
			(layers "B.Cu" "B.Mask" "B.Paste")
			(net "Net_9")
		)
		(pad "41" smd oval
			(at -1.24968 -3.44932)
			(size 0.3048 0.8382)
			(layers "B.Cu" "B.Mask" "B.Paste")
			(net "P52V_HS2_VCC")
		)
		(pad "42" smd oval
			(at 0.24892 -3.44932)
			(size 0.3048 0.8382)
			(layers "B.Cu" "B.Mask" "B.Paste")
			(net "P52V_HS2_VREG")
		)
		(pad "43" smd oval
			(at 0.7493 -3.44932)
			(size 0.3048 0.8382)
			(layers "B.Cu" "B.Mask" "B.Paste")
			(net "P52V_HS2_TEMPN")
		)
		(pad "44" smd oval
			(at 1.24968 -3.44932)
			(size 0.3048 0.8382)
			(layers "B.Cu" "B.Mask" "B.Paste")
			(net "P52V_HS2_TEMPP")
		)
		(pad "45" smd oval
			(at 1.75006 -3.44932)
			(size 0.3048 0.8382)
			(layers "B.Cu" "B.Mask" "B.Paste")
			(net "P52V_HS2_UVH")
		)
		(pad "46" smd oval
			(at 2.25044 -3.44932)
			(size 0.3048 0.8382)
			(layers "B.Cu" "B.Mask" "B.Paste")
			(net "P52V_HS2_UVLO_EN")
		)
		(pad "47" smd oval
			(at 2.75082 -3.44932)
			(size 0.3048 0.8382)
			(layers "B.Cu" "B.Mask" "B.Paste")
			(net "P52V_HS2_OV")
		)
		(pad "48" smd oval
			(at 3.2512 -3.44932)
			(size 0.3048 0.8382)
			(layers "B.Cu" "B.Mask" "B.Paste")
			(net "P52V_HS2_RND")
		)
		(pad "PAD1" smd rect
			(at 1.89738 0)
			(size 2.794 5.588)
			(layers "B.Cu" "B.Mask" "B.Paste")
			(net "GND1_FIELD_SIGNAL")
		)
		(pad "PAD2" smd rect
			(at -1.55194 0)
			(size 1.4986 3.4036)
			(layers "B.Cu" "B.Mask" "B.Paste")
			(net "P52V_HS2_VCC")
		)
		(zone
			(layer "B.Cu")
			(hatch none 0.5)
			(connect_pads
				(clearance 0)
			)
			(min_thickness 0.25)
			(keepout
				(tracks not_allowed)
				(vias allowed)
				(pads allowed)
				(copperpour not_allowed)
				(footprints allowed)
			)
			(placement
				(enabled no)
				(sheetname "")
			)
			(fill
				(thermal_gap 0.5)
				(thermal_bridge_width 0.5)
				(island_removal_mode 0)
			)
			(polygon
				(pts
					(xy 180.945536 -67.6402) (xy 180.945536 -73.5838) (xy 178.227736 -73.5838) (xy 178.227736 -72.3646)
					(xy 179.827936 -72.3646) (xy 179.827936 -68.8594) (xy 178.227736 -68.8594) (xy 178.227736 -67.6402)
				)
			)
		)
		(zone
			(layer "B.Cu")
			(hatch none 0.5)
			(connect_pads
				(clearance 0)
			)
			(min_thickness 0.25)
			(keepout
				(tracks not_allowed)
				(vias allowed)
				(pads allowed)
				(copperpour not_allowed)
				(footprints allowed)
			)
			(placement
				(enabled no)
				(sheetname "")
			)
			(fill
				(thermal_gap 0.5)
				(thermal_bridge_width 0.5)
				(island_removal_mode 0)
			)
			(polygon
				(pts
					(xy 173.985936 -69.2912) (xy 173.985936 -73.5838) (xy 178.202336 -73.5838) (xy 178.202336 -67.6402)
					(xy 173.985936 -67.6402) (xy 173.985936 -69.2658) (xy 174.112936 -69.2658) (xy 174.112936 -67.7672)
					(xy 177.033936 -67.7672) (xy 177.033936 -73.4568) (xy 174.112936 -73.4568) (xy 174.112936 -69.2912)
				)
			)
		)
	)
	(footprint ""
		(layer "B.Cu")
		(at 289.306 -92.075 -90)
		(property "Reference" "C91"
			(at 0 0 90)
			(layer "B.SilkS")
			(hide yes)
			(effects
				(font
					(size 1.27 1.27)
				)
				(justify mirror)
			)
		)
		(property "Value" ""
			(at 0 0 90)
			(layer "B.Fab")
			(effects
				(font
					(size 1.27 1.27)
				)
				(justify mirror)
			)
		)
		(duplicate_pad_numbers_are_jumpers no)
		(fp_line
			(start -0.7874 0.4064)
			(end 0.7874 0.4064)
			(stroke
				(width 0.1524)
				(type default)
			)
			(layer "B.SilkS")
		)
		(fp_line
			(start 0.7874 0.4064)
			(end 0.7874 -0.4064)
			(stroke
				(width 0.1524)
				(type default)
			)
			(layer "B.SilkS")
		)
		(fp_line
			(start -0.7874 -0.4064)
			(end -0.7874 0.4064)
			(stroke
				(width 0.1524)
				(type default)
			)
			(layer "B.SilkS")
		)
		(fp_line
			(start 0.7874 -0.4064)
			(end -0.7874 -0.4064)
			(stroke
				(width 0.1524)
				(type default)
			)
			(layer "B.SilkS")
		)
		(fp_line
			(start -0.67945 0.3048)
			(end -0.120396 0.3048)
			(stroke
				(width 0.1)
				(type default)
			)
			(layer "B.Fab")
		)
		(fp_line
			(start -0.120396 0.3048)
			(end -0.120396 0.2794)
			(stroke
				(width 0.1)
				(type default)
			)
			(layer "B.Fab")
		)
		(fp_line
			(start 0.12065 0.3048)
			(end 0.67945 0.3048)
			(stroke
				(width 0.1)
				(type default)
			)
			(layer "B.Fab")
		)
		(fp_line
			(start 0.67945 0.3048)
			(end 0.67945 -0.305054)
			(stroke
				(width 0.1)
				(type default)
			)
			(layer "B.Fab")
		)
		(fp_line
			(start -0.120396 0.2794)
			(end 0.12065 0.2794)
			(stroke
				(width 0.1)
				(type default)
			)
			(layer "B.Fab")
		)
		(fp_line
			(start 0.12065 0.2794)
			(end 0.12065 0.3048)
			(stroke
				(width 0.1)
				(type default)
			)
			(layer "B.Fab")
		)
		(fp_line
			(start -0.12065 -0.2794)
			(end -0.12065 -0.3048)
			(stroke
				(width 0.1)
				(type default)
			)
			(layer "B.Fab")
		)
		(fp_line
			(start 0.12065 -0.2794)
			(end -0.12065 -0.2794)
			(stroke
				(width 0.1)
				(type default)
			)
			(layer "B.Fab")
		)
		(fp_line
			(start -0.67945 -0.3048)
			(end -0.67945 0.3048)
			(stroke
				(width 0.1)
				(type default)
			)
			(layer "B.Fab")
		)
		(fp_line
			(start -0.12065 -0.3048)
			(end -0.67945 -0.3048)
			(stroke
				(width 0.1)
				(type default)
			)
			(layer "B.Fab")
		)
		(fp_line
			(start 0.12065 -0.305054)
			(end 0.12065 -0.2794)
			(stroke
				(width 0.1)
				(type default)
			)
			(layer "B.Fab")
		)
		(fp_line
			(start 0.67945 -0.305054)
			(end 0.12065 -0.305054)
			(stroke
				(width 0.1)
				(type default)
			)
			(layer "B.Fab")
		)
		(pad "1" smd circle
			(at 0.40005 0 90)
			(size 0 0)
			(layers "B.Cu" "B.Mask" "B.Paste")
			(net "P3V3_AND")
		)
		(pad "2" smd circle
			(at -0.40005 0 90)
			(size 0 0)
			(layers "B.Cu" "B.Mask" "B.Paste")
			(net "GND")
		)
	)
)
